(kicad_pcb
	(version 20260206)
	(generator "pcbnew")
	(generator_version "10.0")
	(general
		(thickness 1.6)
		(legacy_teardrops no)
	)
	(paper "A4")
	(title_block
		(title "03242023_DA0F0TMBIJ0_F0T_Motherboard_J_brd_V01_OCP.brd")
		(comment 1 "Grand Teton / footprints 4778-4783 of 6105")
	)
	(layers
		(0 "F.Cu" signal "TOP")
		(4 "In1.Cu" signal "GND")
		(6 "In2.Cu" signal "IN1")
		(8 "In3.Cu" signal "GND1")
		(10 "In4.Cu" signal "IN2")
		(12 "In5.Cu" signal "GND2")
		(14 "In6.Cu" signal "IN3")
		(16 "In7.Cu" signal "GND3")
		(18 "In8.Cu" signal "VCC")
		(20 "In9.Cu" signal "VCC1")
		(22 "In10.Cu" signal "GND4")
		(24 "In11.Cu" signal "IN4")
		(26 "In12.Cu" signal "GND5")
		(28 "In13.Cu" signal "IN5")
		(30 "In14.Cu" signal "GND6")
		(32 "In15.Cu" signal "IN6")
		(34 "In16.Cu" signal "GND7")
		(2 "B.Cu" signal "BOTTOM")
		(9 "F.Adhes" user "F.Adhesive")
		(11 "B.Adhes" user "B.Adhesive")
		(13 "F.Paste" user "Package Geometry/Pastemask Top")
		(15 "B.Paste" user "Package Geometry/Pastemask Bottom")
		(5 "F.SilkS" user "Ref Des/Silkscreen Top")
		(7 "B.SilkS" user "Ref Des/Silkscreen Bottom")
		(1 "F.Mask" user "Board Geometry/Soldermask Top")
		(3 "B.Mask" user "Board Geometry/Soldermask Bottom")
		(17 "Dwgs.User" user "User.Drawings")
		(19 "Cmts.User" user "User.Comments")
		(21 "Eco1.User" user "User.Eco1")
		(23 "Eco2.User" user "User.Eco2")
		(25 "Edge.Cuts" user "Board Geometry/Outline")
		(27 "Margin" user)
		(31 "F.CrtYd" user "Package Geometry/Place Bound Top")
		(29 "B.CrtYd" user "Package Geometry/Place Bound Bottom")
		(35 "F.Fab" user "Ref Des/Assembly Top")
		(33 "B.Fab" user "Ref Des/Assembly Bottom")
	)
	(footprint ""
		(layer "B.Cu")
		(at 113.78438 -362.703872 180)
		(property "Reference" "PR323"
			(at 0 0 0)
			(layer "B.SilkS")
			(hide yes)
			(effects
				(font
					(size 1.27 1.27)
				)
				(justify mirror)
			)
		)
		(property "Value" ""
			(at 0 0 0)
			(layer "B.Fab")
			(effects
				(font
					(size 1.27 1.27)
				)
				(justify mirror)
			)
		)
		(duplicate_pad_numbers_are_jumpers no)
		(fp_line
			(start 0.7874 0.4064)
			(end 0.7874 -0.4064)
			(stroke
				(width 0.1524)
				(type default)
			)
			(layer "B.SilkS")
		)
		(fp_line
			(start 0.7874 -0.4064)
			(end -0.7874 -0.4064)
			(stroke
				(width 0.1524)
				(type default)
			)
			(layer "B.SilkS")
		)
		(fp_line
			(start -0.7874 0.4064)
			(end 0.7874 0.4064)
			(stroke
				(width 0.1524)
				(type default)
			)
			(layer "B.SilkS")
		)
		(fp_line
			(start -0.7874 -0.4064)
			(end -0.7874 0.4064)
			(stroke
				(width 0.1524)
				(type default)
			)
			(layer "B.SilkS")
		)
		(fp_line
			(start 0.67945 0.3048)
			(end 0.67945 -0.305054)
			(stroke
				(width 0.1)
				(type default)
			)
			(layer "B.Fab")
		)
		(fp_line
			(start 0.67945 -0.305054)
			(end 0.12065 -0.305054)
			(stroke
				(width 0.1)
				(type default)
			)
			(layer "B.Fab")
		)
		(fp_line
			(start 0.12065 0.3048)
			(end 0.67945 0.3048)
			(stroke
				(width 0.1)
				(type default)
			)
			(layer "B.Fab")
		)
		(fp_line
			(start 0.12065 0.2794)
			(end 0.12065 0.3048)
			(stroke
				(width 0.1)
				(type default)
			)
			(layer "B.Fab")
		)
		(fp_line
			(start 0.12065 -0.2794)
			(end -0.12065 -0.2794)
			(stroke
				(width 0.1)
				(type default)
			)
			(layer "B.Fab")
		)
		(fp_line
			(start 0.12065 -0.305054)
			(end 0.12065 -0.2794)
			(stroke
				(width 0.1)
				(type default)
			)
			(layer "B.Fab")
		)
		(fp_line
			(start -0.120396 0.3048)
			(end -0.120396 0.2794)
			(stroke
				(width 0.1)
				(type default)
			)
			(layer "B.Fab")
		)
		(fp_line
			(start -0.120396 0.2794)
			(end 0.12065 0.2794)
			(stroke
				(width 0.1)
				(type default)
			)
			(layer "B.Fab")
		)
		(fp_line
			(start -0.12065 -0.2794)
			(end -0.12065 -0.3048)
			(stroke
				(width 0.1)
				(type default)
			)
			(layer "B.Fab")
		)
		(fp_line
			(start -0.12065 -0.3048)
			(end -0.67945 -0.3048)
			(stroke
				(width 0.1)
				(type default)
			)
			(layer "B.Fab")
		)
		(fp_line
			(start -0.67945 0.3048)
			(end -0.120396 0.3048)
			(stroke
				(width 0.1)
				(type default)
			)
			(layer "B.Fab")
		)
		(fp_line
			(start -0.67945 -0.3048)
			(end -0.67945 0.3048)
			(stroke
				(width 0.1)
				(type default)
			)
			(layer "B.Fab")
		)
		(pad "1" smd circle
			(at 0.40005 0)
			(size 0 0)
			(layers "B.Cu" "B.Mask" "B.Paste")
			(net "PVCCIN_CPU1_VCC")
		)
		(pad "2" smd circle
			(at -0.40005 0)
			(size 0 0)
			(layers "B.Cu" "B.Mask" "B.Paste")
			(net "P3V3_AUX")
		)
	)
	(footprint ""
		(layer "B.Cu")
		(at 351.841308 -259.532882 -90)
		(property "Reference" "C496"
			(at 0 0 90)
			(layer "B.SilkS")
			(hide yes)
			(effects
				(font
					(size 1.27 1.27)
				)
				(justify mirror)
			)
		)
		(property "Value" ""
			(at 0 0 90)
			(layer "B.Fab")
			(effects
				(font
					(size 1.27 1.27)
				)
				(justify mirror)
			)
		)
		(duplicate_pad_numbers_are_jumpers no)
		(fp_line
			(start -1.524 0.762)
			(end 1.524 0.762)
			(stroke
				(width 0.1524)
				(type default)
			)
			(layer "B.SilkS")
		)
		(fp_line
			(start 1.524 0.762)
			(end 1.524 -0.762)
			(stroke
				(width 0.1524)
				(type default)
			)
			(layer "B.SilkS")
		)
		(fp_line
			(start -1.524 -0.762)
			(end -1.524 0.762)
			(stroke
				(width 0.1524)
				(type default)
			)
			(layer "B.SilkS")
		)
		(fp_line
			(start 1.524 -0.762)
			(end -1.524 -0.762)
			(stroke
				(width 0.1524)
				(type default)
			)
			(layer "B.SilkS")
		)
		(fp_line
			(start -1.1049 0.724916)
			(end -1.1049 -0.724916)
			(stroke
				(width 0.1)
				(type default)
			)
			(layer "B.Fab")
		)
		(fp_line
			(start 1.1049 0.724916)
			(end -1.1049 0.724916)
			(stroke
				(width 0.1)
				(type default)
			)
			(layer "B.Fab")
		)
		(fp_line
			(start -1.1049 -0.724916)
			(end 1.1049 -0.724916)
			(stroke
				(width 0.1)
				(type default)
			)
			(layer "B.Fab")
		)
		(fp_line
			(start 1.1049 -0.724916)
			(end 1.1049 0.724916)
			(stroke
				(width 0.1)
				(type default)
			)
			(layer "B.Fab")
		)
		(pad "1" smd rect
			(at 0.889 0 270)
			(size 1.016 1.27)
			(layers "B.Cu" "B.Mask" "B.Paste")
			(net "PVCCFA_EHV_CPU0")
		)
		(pad "2" smd rect
			(at -0.889 0 270)
			(size 1.016 1.27)
			(layers "B.Cu" "B.Mask" "B.Paste")
			(net "GND")
		)
	)
	(footprint ""
		(layer "B.Cu")
		(at 72.401684 -190.744856 90)
		(property "Reference" "R58"
			(at 0 0 90)
			(layer "B.SilkS")
			(hide yes)
			(effects
				(font
					(size 1.27 1.27)
				)
				(justify mirror)
			)
		)
		(property "Value" ""
			(at 0 0 90)
			(layer "B.Fab")
			(effects
				(font
					(size 1.27 1.27)
				)
				(justify mirror)
			)
		)
		(duplicate_pad_numbers_are_jumpers no)
		(fp_line
			(start 0.7874 -0.4064)
			(end -0.7874 -0.4064)
			(stroke
				(width 0.1524)
				(type default)
			)
			(layer "B.SilkS")
		)
		(fp_line
			(start -0.7874 -0.4064)
			(end -0.7874 0.4064)
			(stroke
				(width 0.1524)
				(type default)
			)
			(layer "B.SilkS")
		)
		(fp_line
			(start 0.7874 0.4064)
			(end 0.7874 -0.4064)
			(stroke
				(width 0.1524)
				(type default)
			)
			(layer "B.SilkS")
		)
		(fp_line
			(start -0.7874 0.4064)
			(end 0.7874 0.4064)
			(stroke
				(width 0.1524)
				(type default)
			)
			(layer "B.SilkS")
		)
		(fp_line
			(start 0.67945 -0.305054)
			(end 0.12065 -0.305054)
			(stroke
				(width 0.1)
				(type default)
			)
			(layer "B.Fab")
		)
		(fp_line
			(start 0.12065 -0.305054)
			(end 0.12065 -0.2794)
			(stroke
				(width 0.1)
				(type default)
			)
			(layer "B.Fab")
		)
		(fp_line
			(start -0.12065 -0.3048)
			(end -0.67945 -0.3048)
			(stroke
				(width 0.1)
				(type default)
			)
			(layer "B.Fab")
		)
		(fp_line
			(start -0.67945 -0.3048)
			(end -0.67945 0.3048)
			(stroke
				(width 0.1)
				(type default)
			)
			(layer "B.Fab")
		)
		(fp_line
			(start 0.12065 -0.2794)
			(end -0.12065 -0.2794)
			(stroke
				(width 0.1)
				(type default)
			)
			(layer "B.Fab")
		)
		(fp_line
			(start -0.12065 -0.2794)
			(end -0.12065 -0.3048)
			(stroke
				(width 0.1)
				(type default)
			)
			(layer "B.Fab")
		)
		(fp_line
			(start 0.12065 0.2794)
			(end 0.12065 0.3048)
			(stroke
				(width 0.1)
				(type default)
			)
			(layer "B.Fab")
		)
		(fp_line
			(start -0.120396 0.2794)
			(end 0.12065 0.2794)
			(stroke
				(width 0.1)
				(type default)
			)
			(layer "B.Fab")
		)
		(fp_line
			(start 0.67945 0.3048)
			(end 0.67945 -0.305054)
			(stroke
				(width 0.1)
				(type default)
			)
			(layer "B.Fab")
		)
		(fp_line
			(start 0.12065 0.3048)
			(end 0.67945 0.3048)
			(stroke
				(width 0.1)
				(type default)
			)
			(layer "B.Fab")
		)
		(fp_line
			(start -0.120396 0.3048)
			(end -0.120396 0.2794)
			(stroke
				(width 0.1)
				(type default)
			)
			(layer "B.Fab")
		)
		(fp_line
			(start -0.67945 0.3048)
			(end -0.120396 0.3048)
			(stroke
				(width 0.1)
				(type default)
			)
			(layer "B.Fab")
		)
		(pad "1" smd circle
			(at 0.40005 0 270)
			(size 0 0)
			(layers "B.Cu" "B.Mask" "B.Paste")
			(net "SVID_DIO1_CPU1")
		)
		(pad "2" smd circle
			(at -0.40005 0 270)
			(size 0 0)
			(layers "B.Cu" "B.Mask" "B.Paste")
			(net "SVID_DIO1_CPU1_R")
		)
	)
	(footprint ""
		(layer "B.Cu")
		(at 297.45813 -400.999452 -90)
		(property "Reference" "PR2524"
			(at 0 0 90)
			(layer "B.SilkS")
			(hide yes)
			(effects
				(font
					(size 1.27 1.27)
				)
				(justify mirror)
			)
		)
		(property "Value" ""
			(at 0 0 90)
			(layer "B.Fab")
			(effects
				(font
					(size 1.27 1.27)
				)
				(justify mirror)
			)
		)
		(duplicate_pad_numbers_are_jumpers no)
		(fp_line
			(start -0.7874 0.4064)
			(end 0.7874 0.4064)
			(stroke
				(width 0.1524)
				(type default)
			)
			(layer "B.SilkS")
		)
		(fp_line
			(start 0.7874 0.4064)
			(end 0.7874 -0.4064)
			(stroke
				(width 0.1524)
				(type default)
			)
			(layer "B.SilkS")
		)
		(fp_line
			(start -0.7874 -0.4064)
			(end -0.7874 0.4064)
			(stroke
				(width 0.1524)
				(type default)
			)
			(layer "B.SilkS")
		)
		(fp_line
			(start 0.7874 -0.4064)
			(end -0.7874 -0.4064)
			(stroke
				(width 0.1524)
				(type default)
			)
			(layer "B.SilkS")
		)
		(fp_line
			(start -0.67945 0.3048)
			(end -0.120396 0.3048)
			(stroke
				(width 0.1)
				(type default)
			)
			(layer "B.Fab")
		)
		(fp_line
			(start -0.120396 0.3048)
			(end -0.120396 0.2794)
			(stroke
				(width 0.1)
				(type default)
			)
			(layer "B.Fab")
		)
		(fp_line
			(start 0.12065 0.3048)
			(end 0.67945 0.3048)
			(stroke
				(width 0.1)
				(type default)
			)
			(layer "B.Fab")
		)
		(fp_line
			(start 0.67945 0.3048)
			(end 0.67945 -0.305054)
			(stroke
				(width 0.1)
				(type default)
			)
			(layer "B.Fab")
		)
		(fp_line
			(start -0.120396 0.2794)
			(end 0.12065 0.2794)
			(stroke
				(width 0.1)
				(type default)
			)
			(layer "B.Fab")
		)
		(fp_line
			(start 0.12065 0.2794)
			(end 0.12065 0.3048)
			(stroke
				(width 0.1)
				(type default)
			)
			(layer "B.Fab")
		)
		(fp_line
			(start -0.12065 -0.2794)
			(end -0.12065 -0.3048)
			(stroke
				(width 0.1)
				(type default)
			)
			(layer "B.Fab")
		)
		(fp_line
			(start 0.12065 -0.2794)
			(end -0.12065 -0.2794)
			(stroke
				(width 0.1)
				(type default)
			)
			(layer "B.Fab")
		)
		(fp_line
			(start -0.67945 -0.3048)
			(end -0.67945 0.3048)
			(stroke
				(width 0.1)
				(type default)
			)
			(layer "B.Fab")
		)
		(fp_line
			(start -0.12065 -0.3048)
			(end -0.67945 -0.3048)
			(stroke
				(width 0.1)
				(type default)
			)
			(layer "B.Fab")
		)
		(fp_line
			(start 0.12065 -0.305054)
			(end 0.12065 -0.2794)
			(stroke
				(width 0.1)
				(type default)
			)
			(layer "B.Fab")
		)
		(fp_line
			(start 0.67945 -0.305054)
			(end 0.12065 -0.305054)
			(stroke
				(width 0.1)
				(type default)
			)
			(layer "B.Fab")
		)
		(pad "1" smd circle
			(at 0.40005 0 90)
			(size 0 0)
			(layers "B.Cu" "B.Mask" "B.Paste")
			(net "P12V_HSC_SENSE2_N")
		)
		(pad "2" smd circle
			(at -0.40005 0 90)
			(size 0 0)
			(layers "B.Cu" "B.Mask" "B.Paste")
			(net "P12V_HSC_SENSE2_R1_N")
		)
	)
	(footprint ""
		(layer "B.Cu")
		(at 338.4042 -52.0446 180)
		(property "Reference" "R4803"
			(at 0 0 0)
			(layer "B.SilkS")
			(hide yes)
			(effects
				(font
					(size 1.27 1.27)
				)
				(justify mirror)
			)
		)
		(property "Value" ""
			(at 0 0 0)
			(layer "B.Fab")
			(effects
				(font
					(size 1.27 1.27)
				)
				(justify mirror)
			)
		)
		(duplicate_pad_numbers_are_jumpers no)
		(fp_line
			(start 0.7874 0.4064)
			(end 0.7874 -0.4064)
			(stroke
				(width 0.1524)
				(type default)
			)
			(layer "B.SilkS")
		)
		(fp_line
			(start 0.7874 -0.4064)
			(end -0.7874 -0.4064)
			(stroke
				(width 0.1524)
				(type default)
			)
			(layer "B.SilkS")
		)
		(fp_line
			(start -0.7874 0.4064)
			(end 0.7874 0.4064)
			(stroke
				(width 0.1524)
				(type default)
			)
			(layer "B.SilkS")
		)
		(fp_line
			(start -0.7874 -0.4064)
			(end -0.7874 0.4064)
			(stroke
				(width 0.1524)
				(type default)
			)
			(layer "B.SilkS")
		)
		(fp_line
			(start 0.67945 0.3048)
			(end 0.67945 -0.305054)
			(stroke
				(width 0.1)
				(type default)
			)
			(layer "B.Fab")
		)
		(fp_line
			(start 0.67945 -0.305054)
			(end 0.12065 -0.305054)
			(stroke
				(width 0.1)
				(type default)
			)
			(layer "B.Fab")
		)
		(fp_line
			(start 0.12065 0.3048)
			(end 0.67945 0.3048)
			(stroke
				(width 0.1)
				(type default)
			)
			(layer "B.Fab")
		)
		(fp_line
			(start 0.12065 0.2794)
			(end 0.12065 0.3048)
			(stroke
				(width 0.1)
				(type default)
			)
			(layer "B.Fab")
		)
		(fp_line
			(start 0.12065 -0.2794)
			(end -0.12065 -0.2794)
			(stroke
				(width 0.1)
				(type default)
			)
			(layer "B.Fab")
		)
		(fp_line
			(start 0.12065 -0.305054)
			(end 0.12065 -0.2794)
			(stroke
				(width 0.1)
				(type default)
			)
			(layer "B.Fab")
		)
		(fp_line
			(start -0.120396 0.3048)
			(end -0.120396 0.2794)
			(stroke
				(width 0.1)
				(type default)
			)
			(layer "B.Fab")
		)
		(fp_line
			(start -0.120396 0.2794)
			(end 0.12065 0.2794)
			(stroke
				(width 0.1)
				(type default)
			)
			(layer "B.Fab")
		)
		(fp_line
			(start -0.12065 -0.2794)
			(end -0.12065 -0.3048)
			(stroke
				(width 0.1)
				(type default)
			)
			(layer "B.Fab")
		)
		(fp_line
			(start -0.12065 -0.3048)
			(end -0.67945 -0.3048)
			(stroke
				(width 0.1)
				(type default)
			)
			(layer "B.Fab")
		)
		(fp_line
			(start -0.67945 0.3048)
			(end -0.120396 0.3048)
			(stroke
				(width 0.1)
				(type default)
			)
			(layer "B.Fab")
		)
		(fp_line
			(start -0.67945 -0.3048)
			(end -0.67945 0.3048)
			(stroke
				(width 0.1)
				(type default)
			)
			(layer "B.Fab")
		)
		(pad "1" smd circle
			(at 0.40005 0)
			(size 0 0)
			(layers "B.Cu" "B.Mask" "B.Paste")
			(net "P1V05_PCH_AUX")
		)
		(pad "2" smd circle
			(at -0.40005 0)
			(size 0 0)
			(layers "B.Cu" "B.Mask" "B.Paste")
			(net "P1V05_PCH_PLL_AUX")
		)
	)
	(footprint ""
		(layer "B.Cu")
		(at 312.578242 -39.794688 180)
		(property "Reference" "R1498"
			(at 0 0 0)
			(layer "B.SilkS")
			(hide yes)
			(effects
				(font
					(size 1.27 1.27)
				)
				(justify mirror)
			)
		)
		(property "Value" ""
			(at 0 0 0)
			(layer "B.Fab")
			(effects
				(font
					(size 1.27 1.27)
				)
				(justify mirror)
			)
		)
		(duplicate_pad_numbers_are_jumpers no)
		(fp_line
			(start 0.7874 0.4064)
			(end 0.7874 -0.4064)
			(stroke
				(width 0.1524)
				(type default)
			)
			(layer "B.SilkS")
		)
		(fp_line
			(start 0.7874 -0.4064)
			(end -0.7874 -0.4064)
			(stroke
				(width 0.1524)
				(type default)
			)
			(layer "B.SilkS")
		)
		(fp_line
			(start -0.7874 0.4064)
			(end 0.7874 0.4064)
			(stroke
				(width 0.1524)
				(type default)
			)
			(layer "B.SilkS")
		)
		(fp_line
			(start -0.7874 -0.4064)
			(end -0.7874 0.4064)
			(stroke
				(width 0.1524)
				(type default)
			)
			(layer "B.SilkS")
		)
		(fp_line
			(start 0.67945 0.3048)
			(end 0.67945 -0.305054)
			(stroke
				(width 0.1)
				(type default)
			)
			(layer "B.Fab")
		)
		(fp_line
			(start 0.67945 -0.305054)
			(end 0.12065 -0.305054)
			(stroke
				(width 0.1)
				(type default)
			)
			(layer "B.Fab")
		)
		(fp_line
			(start 0.12065 0.3048)
			(end 0.67945 0.3048)
			(stroke
				(width 0.1)
				(type default)
			)
			(layer "B.Fab")
		)
		(fp_line
			(start 0.12065 0.2794)
			(end 0.12065 0.3048)
			(stroke
				(width 0.1)
				(type default)
			)
			(layer "B.Fab")
		)
		(fp_line
			(start 0.12065 -0.2794)
			(end -0.12065 -0.2794)
			(stroke
				(width 0.1)
				(type default)
			)
			(layer "B.Fab")
		)
		(fp_line
			(start 0.12065 -0.305054)
			(end 0.12065 -0.2794)
			(stroke
				(width 0.1)
				(type default)
			)
			(layer "B.Fab")
		)
		(fp_line
			(start -0.120396 0.3048)
			(end -0.120396 0.2794)
			(stroke
				(width 0.1)
				(type default)
			)
			(layer "B.Fab")
		)
		(fp_line
			(start -0.120396 0.2794)
			(end 0.12065 0.2794)
			(stroke
				(width 0.1)
				(type default)
			)
			(layer "B.Fab")
		)
		(fp_line
			(start -0.12065 -0.2794)
			(end -0.12065 -0.3048)
			(stroke
				(width 0.1)
				(type default)
			)
			(layer "B.Fab")
		)
		(fp_line
			(start -0.12065 -0.3048)
			(end -0.67945 -0.3048)
			(stroke
				(width 0.1)
				(type default)
			)
			(layer "B.Fab")
		)
		(fp_line
			(start -0.67945 0.3048)
			(end -0.120396 0.3048)
			(stroke
				(width 0.1)
				(type default)
			)
			(layer "B.Fab")
		)
		(fp_line
			(start -0.67945 -0.3048)
			(end -0.67945 0.3048)
			(stroke
				(width 0.1)
				(type default)
			)
			(layer "B.Fab")
		)
		(pad "1" smd circle
			(at 0.40005 0)
			(size 0 0)
			(layers "B.Cu" "B.Mask" "B.Paste")
			(net "P1V05_PCH_AUX")
		)
		(pad "2" smd circle
			(at -0.40005 0)
			(size 0 0)
			(layers "B.Cu" "B.Mask" "B.Paste")
			(net "FM_BIOS_ADV_FUNCTIONS")
		)
	)
)
